(kicad_pcb
	(version 20241229)
	(generator "pcbnew")
	(generator_version "9.0")
	(general
		(thickness 1.711)
		(legacy_teardrops no)
	)
	(paper "A4")
	(title_block
		(title "Antmicro Baseboard for Jetson AGX Thor")
		(date "2026-02-18")
		(rev "1.1.0")
		(company "Antmicro Ltd")
		(comment 1 "www.antmicro.com")
		(comment 9 "footprints 187-190 of 1170")
	)
	(layers
		(0 "F.Cu" signal)
		(4 "In1.Cu" signal)
		(6 "In2.Cu" signal)
		(8 "In3.Cu" signal)
		(10 "In4.Cu" jumper)
		(12 "In5.Cu" signal)
		(14 "In6.Cu" signal)
		(16 "In7.Cu" signal)
		(18 "In8.Cu" signal)
		(2 "B.Cu" signal)
		(9 "F.Adhes" user "F.Adhesive")
		(11 "B.Adhes" user "B.Adhesive")
		(13 "F.Paste" user)
		(15 "B.Paste" user)
		(5 "F.SilkS" user "F.Silkscreen")
		(7 "B.SilkS" user "B.Silkscreen")
		(1 "F.Mask" user)
		(3 "B.Mask" user)
		(17 "Dwgs.User" user "User.Drawings")
		(19 "Cmts.User" user "User.Comments")
		(21 "Eco1.User" user "User.Eco1")
		(23 "Eco2.User" user "User.Eco2")
		(25 "Edge.Cuts" user)
		(27 "Margin" user)
		(31 "F.CrtYd" user "F.Courtyard")
		(29 "B.CrtYd" user "B.Courtyard")
		(35 "F.Fab" user)
		(33 "B.Fab" user)
	)
	(footprint "antmicro-footprints:C_0805_2012Metric"
		(layer "F.Cu")
		(at 115.12 56.74 -90)
		(descr "Capacitor SMD 0805")
		(tags "capacitor SMD 0805")
		(property "Reference" "C378"
			(at -1.87 0.05 180)
			(layer "F.SilkS")
			(effects
				(font
					(size 0.7 0.7)
					(thickness 0.15)
				)
				(justify left bottom)
			)
		)
		(property "Value" "C_22u_25V_0805"
			(at -2.055717 1.963152 90)
			(layer "F.Fab")
			(effects
				(font
					(size 0.7 0.7)
					(thickness 0.15)
				)
				(justify right top)
			)
		)
		(property "Datasheet" "https://product.samsungsem.com/mlcc/CL21A226MAYNNN.do"
			(at 0 0 90)
			(layer "F.Fab")
			(hide yes)
			(effects
				(font
					(size 1.27 1.27)
					(thickness 0.15)
				)
			)
		)
		(property "Description" "SMT Multilayer Ceramic Capacitor, 22uF, +/-20%, 25V, X5R, 0805 [2012 Metric]"
			(at 0 0 90)
			(layer "F.Fab")
			(hide yes)
			(effects
				(font
					(size 1.27 1.27)
					(thickness 0.15)
				)
			)
		)
		(property "MPN" "CL21A226MAYNNNE"
			(at 0 0 270)
			(unlocked yes)
			(layer "F.Fab")
			(hide yes)
			(effects
				(font
					(size 1 1)
					(thickness 0.15)
				)
			)
		)
		(property "Manufacturer" "Samsung Electro-Mechanics"
			(at 0 0 270)
			(unlocked yes)
			(layer "F.Fab")
			(hide yes)
			(effects
				(font
					(size 1 1)
					(thickness 0.15)
				)
			)
		)
		(property "License" "Apache-2.0"
			(at 0 0 270)
			(unlocked yes)
			(layer "F.Fab")
			(hide yes)
			(effects
				(font
					(size 1 1)
					(thickness 0.15)
				)
			)
		)
		(property "Author" "Antmicro"
			(at 0 0 270)
			(unlocked yes)
			(layer "F.Fab")
			(hide yes)
			(effects
				(font
					(size 1 1)
					(thickness 0.15)
				)
			)
		)
		(property "Val" "22u"
			(at 0 0 270)
			(unlocked yes)
			(layer "F.Fab")
			(hide yes)
			(effects
				(font
					(size 1 1)
					(thickness 0.15)
				)
			)
		)
		(property "Voltage" "25V"
			(at 0 0 270)
			(unlocked yes)
			(layer "F.Fab")
			(hide yes)
			(effects
				(font
					(size 1 1)
					(thickness 0.15)
				)
			)
		)
		(property "Dielectric" "X5R"
			(at 0 0 270)
			(unlocked yes)
			(layer "F.Fab")
			(hide yes)
			(effects
				(font
					(size 1 1)
					(thickness 0.15)
				)
			)
		)
		(property "Public" "False"
			(at 0 0 270)
			(unlocked yes)
			(layer "F.Fab")
			(hide yes)
			(effects
				(font
					(size 1 1)
					(thickness 0.15)
				)
			)
		)
		(sheetname "/DCDC/")
		(sheetfile "dcdc.kicad_sch")
		(attr smd)
		(fp_line
			(start -0.3 0.7)
			(end 0.3 0.7)
			(stroke
				(width 0.15)
				(type solid)
			)
			(layer "F.SilkS")
		)
		(fp_line
			(start -0.3 -0.7)
			(end 0.3 -0.7)
			(stroke
				(width 0.15)
				(type solid)
			)
			(layer "F.SilkS")
		)
		(fp_rect
			(start 1.95 -0.9)
			(end -1.95 0.9)
			(stroke
				(width 0.05)
				(type default)
			)
			(fill no)
			(layer "F.CrtYd")
		)
		(fp_rect
			(start -0.95 -0.675)
			(end 0.95 0.675)
			(stroke
				(width 0.15)
				(type solid)
			)
			(fill no)
			(layer "F.Fab")
		)
		(fp_text user "${REFERENCE}"
			(at -1.9 3.947 90)
			(layer "F.Fab")
			(effects
				(font
					(size 0.7 0.7)
					(thickness 0.15)
				)
				(justify right top)
			)
		)
		(fp_text user "Author: Antmicro"
			(at -1.9 5.947 90)
			(layer "F.Fab")
			(effects
				(font
					(size 0.7 0.7)
					(thickness 0.15)
				)
				(justify right top)
			)
		)
		(fp_text user "License: Apache-2.0"
			(at -1.9 4.947 90)
			(layer "F.Fab")
			(effects
				(font
					(size 0.7 0.7)
					(thickness 0.15)
				)
				(justify right top)
			)
		)
		(pad "1" smd roundrect
			(at -1.1 0 270)
			(size 1.2 1.3)
			(layers "F.Cu" "F.Mask" "F.Paste")
			(roundrect_rratio 0.25)
			(net 1 "GND")
			(pintype "passive")
		)
		(pad "2" smd roundrect
			(at 1.1 0 270)
			(size 1.2 1.3)
			(layers "F.Cu" "F.Mask" "F.Paste")
			(roundrect_rratio 0.25)
			(net 1278 "/DCDC/5V_{AON}_OUT")
			(pintype "passive")
		)
	)
	(footprint "antmicro-footprints:USON-10_2.5x1mm_P0.5mm"
		(layer "F.Cu")
		(at 220.853 131.573 180)
		(descr "USON-10 2.5x1mm_ Pitch 0.5mm")
		(tags "USON-10 2.5x1mm Pitch 0.5mm")
		(property "Reference" "U19"
			(at -1.107 0.393 90)
			(layer "F.SilkS")
			(effects
				(font
					(size 0.7 0.7)
					(thickness 0.15)
				)
				(justify right top)
			)
		)
		(property "Value" "TPD4E05U06QDQARQ1"
			(at 0.018 2.499 0)
			(layer "F.Fab")
			(effects
				(font
					(size 0.7 0.7)
					(thickness 0.15)
				)
				(justify right top)
			)
		)
		(property "Datasheet" "https://www.ti.com/lit/ds/symlink/tpd4e05u06-q1.pdf?HQS=dis-mous-null-mousermode-dsf-pf-null-wwe&ts=1663591265741&ref_url=https%253A%252F%252Fwww.mouser.com%252F"
			(at 0 0 0)
			(layer "F.Fab")
			(hide yes)
			(effects
				(font
					(size 1.27 1.27)
					(thickness 0.15)
				)
			)
		)
		(property "Description" "TVS diode array, 12 kV, USON-10, 5.5 V, 0.5 pF"
			(at 0 0 0)
			(layer "F.Fab")
			(hide yes)
			(effects
				(font
					(size 1.27 1.27)
					(thickness 0.15)
				)
			)
		)
		(property "Manufacturer" "Texas Instruments"
			(at 0 0 180)
			(unlocked yes)
			(layer "F.Fab")
			(hide yes)
			(effects
				(font
					(size 1 1)
					(thickness 0.15)
				)
			)
		)
		(property "MPN" "TPD4E05U06QDQARQ1"
			(at 0 0 180)
			(unlocked yes)
			(layer "F.Fab")
			(hide yes)
			(effects
				(font
					(size 1 1)
					(thickness 0.15)
				)
			)
		)
		(property "Author" "Antmicro"
			(at 0 0 180)
			(unlocked yes)
			(layer "F.Fab")
			(hide yes)
			(effects
				(font
					(size 1 1)
					(thickness 0.15)
				)
			)
		)
		(property "License" "Apache-2.0"
			(at 0 0 180)
			(unlocked yes)
			(layer "F.Fab")
			(hide yes)
			(effects
				(font
					(size 1 1)
					(thickness 0.15)
				)
			)
		)
		(sheetname "/USB Hub/")
		(sheetfile "usb_hub.kicad_sch")
		(attr smd)
		(fp_line
			(start 0.498 1.398)
			(end -0.5 1.398)
			(stroke
				(width 0.15)
				(type solid)
			)
			(layer "F.SilkS")
		)
		(fp_line
			(start 0.498 -1.401)
			(end -0.5 -1.401)
			(stroke
				(width 0.15)
				(type solid)
			)
			(layer "F.SilkS")
		)
		(fp_circle
			(center -0.68 -1.27)
			(end -0.63 -1.27)
			(stroke
				(width 0.15)
				(type solid)
			)
			(fill yes)
			(layer "F.SilkS")
		)
		(fp_rect
			(start -0.8 -1.5)
			(end 0.8 1.499)
			(stroke
				(width 0.05)
				(type solid)
			)
			(fill no)
			(layer "F.CrtYd")
		)
		(fp_line
			(start 0.498 -1.25)
			(end 0.498 1.249)
			(stroke
				(width 0.15)
				(type solid)
			)
			(layer "F.Fab")
		)
		(fp_line
			(start 0.498 -1.25)
			(end -0.25 -1.25)
			(stroke
				(width 0.15)
				(type solid)
			)
			(layer "F.Fab")
		)
		(fp_line
			(start -0.25 -1.25)
			(end -0.5 -1)
			(stroke
				(width 0.15)
				(type solid)
			)
			(layer "F.Fab")
		)
		(fp_line
			(start -0.5 1.249)
			(end 0.498 1.249)
			(stroke
				(width 0.15)
				(type solid)
			)
			(layer "F.Fab")
		)
		(fp_line
			(start -0.5 -1)
			(end -0.5 1.249)
			(stroke
				(width 0.15)
				(type solid)
			)
			(layer "F.Fab")
		)
		(fp_text user "License: Apache-2.0"
			(at -0.802 6.9 0)
			(layer "F.Fab")
			(effects
				(font
					(size 0.7 0.7)
					(thickness 0.15)
				)
				(justify right top)
			)
		)
		(fp_text user "Author: Antmicro"
			(at -0.802 5.7 0)
			(layer "F.Fab")
			(effects
				(font
					(size 0.7 0.7)
					(thickness 0.15)
				)
				(justify right top)
			)
		)
		(fp_text user "${REFERENCE}"
			(at -0.802 4.498 0)
			(layer "F.Fab")
			(effects
				(font
					(size 0.7 0.7)
					(thickness 0.15)
				)
				(justify right top)
			)
		)
		(pad "1" smd roundrect
			(at -0.387 -1 90)
			(size 0.25 0.55)
			(layers "F.Cu" "F.Mask" "F.Paste")
			(roundrect_rratio 0.25)
			(net 78 "/USB Hub/USBC4_CONN_TX1_P")
			(pintype "passive")
		)
		(pad "2" smd roundrect
			(at -0.387 -0.5 90)
			(size 0.25 0.55)
			(layers "F.Cu" "F.Mask" "F.Paste")
			(roundrect_rratio 0.25)
			(net 91 "/USB Hub/USBC4_CONN_TX1_N")
			(pintype "passive")
		)
		(pad "3" smd roundrect
			(at -0.387 0 90)
			(size 0.4 0.55)
			(layers "F.Cu" "F.Mask" "F.Paste")
			(roundrect_rratio 0.25)
			(net 1 "GND")
			(pintype "power_in")
		)
		(pad "4" smd roundrect
			(at -0.387 0.498 90)
			(size 0.25 0.55)
			(layers "F.Cu" "F.Mask" "F.Paste")
			(roundrect_rratio 0.25)
			(net 504 "/USB Hub/USBC4_RX_{1}+")
			(pintype "passive")
		)
		(pad "5" smd roundrect
			(at -0.387 0.998 90)
			(size 0.25 0.55)
			(layers "F.Cu" "F.Mask" "F.Paste")
			(roundrect_rratio 0.25)
			(net 501 "/USB Hub/USBC4_RX_{1}-")
			(pintype "passive")
		)
		(pad "6" smd roundrect
			(at 0.385 0.998 90)
			(size 0.25 0.55)
			(layers "F.Cu" "F.Mask" "F.Paste")
			(roundrect_rratio 0.25)
			(net 501 "/USB Hub/USBC4_RX_{1}-")
			(pintype "passive")
		)
		(pad "7" smd roundrect
			(at 0.385 0.498 90)
			(size 0.25 0.55)
			(layers "F.Cu" "F.Mask" "F.Paste")
			(roundrect_rratio 0.25)
			(net 504 "/USB Hub/USBC4_RX_{1}+")
			(pintype "passive")
		)
		(pad "8" smd roundrect
			(at 0.385 0 90)
			(size 0.4 0.55)
			(layers "F.Cu" "F.Mask" "F.Paste")
			(roundrect_rratio 0.25)
			(net 1 "GND")
			(pintype "passive")
		)
		(pad "9" smd roundrect
			(at 0.385 -0.5 90)
			(size 0.25 0.55)
			(layers "F.Cu" "F.Mask" "F.Paste")
			(roundrect_rratio 0.25)
			(net 91 "/USB Hub/USBC4_CONN_TX1_N")
			(pintype "passive")
		)
		(pad "10" smd roundrect
			(at 0.385 -1 90)
			(size 0.25 0.55)
			(layers "F.Cu" "F.Mask" "F.Paste")
			(roundrect_rratio 0.25)
			(net 78 "/USB Hub/USBC4_CONN_TX1_P")
			(pintype "passive")
		)
	)
	(footprint "antmicro-footprints:Oscillator_SMD_ECS_2016MV_2x1.6x0.85mm"
		(layer "F.Cu")
		(at 210.8 135.2 180)
		(property "Reference" "Y2"
			(at -3.1 -0.6 90)
			(layer "F.SilkS")
			(effects
				(font
					(size 0.7 0.7)
					(thickness 0.15)
				)
				(justify left bottom)
			)
		)
		(property "Value" "Oscillator_25MHz_ESC_2016MV"
			(at 0 2.2 0)
			(layer "F.Fab")
			(effects
				(font
					(size 0.7 0.7)
					(thickness 0.15)
				)
				(justify right top)
			)
		)
		(property "Datasheet" "https://ecsxtal.com/store/pdf/ECS-2016MV.pdf"
			(at 0 0 0)
			(layer "F.Fab")
			(hide yes)
			(effects
				(font
					(size 1.27 1.27)
					(thickness 0.15)
				)
			)
		)
		(property "Description" "Oscillator, 25 MHz, HCMOS, SMD, 2mm x 1.6mm, MultiVolt ECS-2016MV Series"
			(at 0 0 0)
			(layer "F.Fab")
			(hide yes)
			(effects
				(font
					(size 1.27 1.27)
					(thickness 0.15)
				)
			)
		)
		(property "MPN" "ECS-2016MV-250-CN-TR"
			(at 0 0 180)
			(unlocked yes)
			(layer "F.Fab")
			(hide yes)
			(effects
				(font
					(size 1 1)
					(thickness 0.15)
				)
			)
		)
		(property "Manufacturer" "ECS Inc. International"
			(at 0 0 180)
			(unlocked yes)
			(layer "F.Fab")
			(hide yes)
			(effects
				(font
					(size 1 1)
					(thickness 0.15)
				)
			)
		)
		(property "Val" "25 MHz"
			(at 0 0 180)
			(unlocked yes)
			(layer "F.Fab")
			(hide yes)
			(effects
				(font
					(size 1 1)
					(thickness 0.15)
				)
			)
		)
		(property "Author" "Antmicro"
			(at 0 0 180)
			(unlocked yes)
			(layer "F.Fab")
			(hide yes)
			(effects
				(font
					(size 1 1)
					(thickness 0.15)
				)
			)
		)
		(property "License" "Apache-2.0"
			(at 0 0 180)
			(unlocked yes)
			(layer "F.Fab")
			(hide yes)
			(effects
				(font
					(size 1 1)
					(thickness 0.15)
				)
			)
		)
		(sheetname "/USB Hub/")
		(sheetfile "usb_hub.kicad_sch")
		(attr smd)
		(fp_line
			(start 0.95 0.4)
			(end 0.95 -0.4)
			(stroke
				(width 0.15)
				(type solid)
			)
			(layer "F.SilkS")
		)
		(fp_line
			(start -0.4 1.15)
			(end 0.4 1.15)
			(stroke
				(width 0.15)
				(type solid)
			)
			(layer "F.SilkS")
		)
		(fp_line
			(start -0.4 -1.15)
			(end 0.4 -1.15)
			(stroke
				(width 0.15)
				(type solid)
			)
			(layer "F.SilkS")
		)
		(fp_line
			(start -0.95 0.4)
			(end -0.95 -0.4)
			(stroke
				(width 0.15)
				(type solid)
			)
			(layer "F.SilkS")
		)
		(fp_circle
			(center -0.95 -1.15)
			(end -0.9 -1.15)
			(stroke
				(width 0.15)
				(type solid)
			)
			(fill yes)
			(layer "F.SilkS")
		)
		(fp_rect
			(start -1.05 -1.25)
			(end 1.05 1.24)
			(stroke
				(width 0.05)
				(type solid)
			)
			(fill no)
			(layer "F.CrtYd")
		)
		(fp_rect
			(start -0.85 -1.054)
			(end 0.852 1.054)
			(stroke
				(width 0.15)
				(type solid)
			)
			(fill no)
			(layer "F.Fab")
		)
		(fp_text user "${REFERENCE}"
			(at -1.05 3.4 0)
			(layer "F.Fab")
			(effects
				(font
					(size 0.7 0.7)
					(thickness 0.15)
				)
				(justify right top)
			)
		)
		(fp_text user "License: Apache-2.0"
			(at -1.05 5.8 0)
			(layer "F.Fab")
			(effects
				(font
					(size 0.7 0.7)
					(thickness 0.15)
				)
				(justify right top)
			)
		)
		(fp_text user "Author: Antmicro"
			(at -1.05 4.6 0)
			(layer "F.Fab")
			(effects
				(font
					(size 0.7 0.7)
					(thickness 0.15)
				)
				(justify right top)
			)
		)
		(pad "1" smd rect
			(at -0.486 -0.637 180)
			(size 0.6858 0.7874)
			(layers "F.Cu" "F.Mask" "F.Paste")
			(net 2 "+3V3")
			(pinfunction "EN")
			(pintype "input")
		)
		(pad "2" smd rect
			(at -0.486 0.636 180)
			(size 0.6858 0.7874)
			(layers "F.Cu" "F.Mask" "F.Paste")
			(net 1 "GND")
			(pinfunction "GND")
			(pintype "power_in")
		)
		(pad "3" smd rect
			(at 0.487 0.636 180)
			(size 0.6858 0.7874)
			(layers "F.Cu" "F.Mask" "F.Paste")
			(net 1078 "Net-(U21-XTALI)")
			(pinfunction "OUT")
			(pintype "output")
		)
		(pad "4" smd rect
			(at 0.487 -0.637 180)
			(size 0.6858 0.7874)
			(layers "F.Cu" "F.Mask" "F.Paste")
			(net 2 "+3V3")
			(pinfunction "VDD")
			(pintype "power_in")
		)
	)
	(footprint "antmicro-footprints:R_0402_1005Metric"
		(layer "F.Cu")
		(at 143.56 135.04 180)
		(descr "Resistor SMD 0402")
		(tags "resistor SMD 0402")
		(property "Reference" "R60"
			(at -1.122484 -0.772697 0)
			(layer "F.SilkS")
			(effects
				(font
					(size 0.7 0.7)
					(thickness 0.15)
				)
				(justify right top)
			)
		)
		(property "Value" "R_470R_0402"
			(at -1.011843 1.772047 0)
			(layer "F.Fab")
			(effects
				(font
					(size 0.7 0.7)
					(thickness 0.15)
				)
				(justify right top)
			)
		)
		(property "Datasheet" "https://www.bourns.com/docs/product-datasheets/cr.pdf"
			(at 0 0 0)
			(layer "F.Fab")
			(hide yes)
			(effects
				(font
					(size 1.27 1.27)
					(thickness 0.15)
				)
			)
		)
		(property "Description" "SMD Chip Resistor, 470 ohm, ± 1%, 62.5 mW, 0402 [1005 Metric], Thick Film, General Purpose"
			(at 0 0 0)
			(layer "F.Fab")
			(hide yes)
			(effects
				(font
					(size 1.27 1.27)
					(thickness 0.15)
				)
			)
		)
		(property "MPN" "CR0402-FX-4700GLF"
			(at 0 0 180)
			(unlocked yes)
			(layer "F.Fab")
			(hide yes)
			(effects
				(font
					(size 1 1)
					(thickness 0.15)
				)
			)
		)
		(property "Manufacturer" "Bourns"
			(at 0 0 180)
			(unlocked yes)
			(layer "F.Fab")
			(hide yes)
			(effects
				(font
					(size 1 1)
					(thickness 0.15)
				)
			)
		)
		(property "License" "Apache-2.0"
			(at 0 0 180)
			(unlocked yes)
			(layer "F.Fab")
			(hide yes)
			(effects
				(font
					(size 1 1)
					(thickness 0.15)
				)
			)
		)
		(property "Author" "Antmicro"
			(at 0 0 180)
			(unlocked yes)
			(layer "F.Fab")
			(hide yes)
			(effects
				(font
					(size 1 1)
					(thickness 0.15)
				)
			)
		)
		(property "Val" "470R"
			(at 0 0 180)
			(unlocked yes)
			(layer "F.Fab")
			(hide yes)
			(effects
				(font
					(size 1 1)
					(thickness 0.15)
				)
			)
		)
		(property "Tolerance" "1%"
			(at 0 0 180)
			(unlocked yes)
			(layer "F.Fab")
			(hide yes)
			(effects
				(font
					(size 1 1)
					(thickness 0.15)
				)
			)
		)
		(sheetname "/SoM_Power/")
		(sheetfile "som_power.kicad_sch")
		(attr smd)
		(fp_rect
			(start -0.925 -0.47)
			(end 0.925 0.47)
			(stroke
				(width 0.05)
				(type default)
			)
			(fill no)
			(layer "F.CrtYd")
		)
		(fp_rect
			(start -0.5 -0.25)
			(end 0.5 0.25)
			(stroke
				(width 0.15)
				(type solid)
			)
			(fill no)
			(layer "F.Fab")
		)
		(fp_text user "License: Apache-2.0"
			(at -0.95 5.169 0)
			(layer "F.Fab")
			(effects
				(font
					(size 0.7 0.7)
					(thickness 0.15)
				)
				(justify right top)
			)
		)
		(fp_text user "Author: Antmicro"
			(at -0.95 4.169 0)
			(layer "F.Fab")
			(effects
				(font
					(size 0.7 0.7)
					(thickness 0.15)
				)
				(justify right top)
			)
		)
		(fp_text user "${REFERENCE}"
			(at -0.95 3.168 0)
			(layer "F.Fab")
			(effects
				(font
					(size 0.7 0.7)
					(thickness 0.15)
				)
				(justify right top)
			)
		)
		(pad "1" smd roundrect
			(at -0.48 0 180)
			(size 0.59 0.64)
			(layers "F.Cu" "F.Mask" "F.Paste")
			(roundrect_rratio 0.25)
			(net 1303 "Net-(Q38-D)")
			(pintype "passive")
		)
		(pad "2" smd roundrect
			(at 0.48 0 180)
			(size 0.59 0.64)
			(layers "F.Cu" "F.Mask" "F.Paste")
			(roundrect_rratio 0.25)
			(net 11 "+1V8")
			(pintype "passive")
		)
	)
)
